(kicad_pcb
	(version 20241229)
	(generator "pcbnew")
	(generator_version "9.0")
	(general
		(thickness 1.294)
		(legacy_teardrops no)
	)
	(paper "A3")
	(title_block
		(title "Kintex 410T devboard")
		(date "2024-04-03")
		(rev "1.1.2")
		(comment 9 "footprints 741-745 of 975")
	)
	(layers
		(0 "F.Cu" mixed)
		(4 "In1.Cu" power)
		(6 "In2.Cu" power)
		(8 "In3.Cu" mixed)
		(10 "In4.Cu" power)
		(12 "In5.Cu" mixed)
		(14 "In6.Cu" power)
		(16 "In7.Cu" mixed)
		(18 "In8.Cu" power)
		(2 "B.Cu" mixed)
		(9 "F.Adhes" user "F.Adhesive")
		(11 "B.Adhes" user "B.Adhesive")
		(13 "F.Paste" user)
		(15 "B.Paste" user)
		(5 "F.SilkS" user "F.Silkscreen")
		(7 "B.SilkS" user "B.Silkscreen")
		(1 "F.Mask" user)
		(3 "B.Mask" user)
		(17 "Dwgs.User" user "User.Drawings")
		(19 "Cmts.User" user "User.Comments")
		(21 "Eco1.User" user "User.Eco1")
		(23 "Eco2.User" user "User.Eco2")
		(25 "Edge.Cuts" user)
		(27 "Margin" user)
		(31 "F.CrtYd" user "F.Courtyard")
		(29 "B.CrtYd" user "B.Courtyard")
		(35 "F.Fab" user)
		(33 "B.Fab" user)
	)
	(footprint "antmicro-footprints:C_0402_1005Metric"
		(layer "B.Cu")
		(at 192 118.3)
		(descr "Capacitor SMD 0402")
		(tags "capacitor SMD 0402")
		(property "Reference" "C119"
			(at 1.475 1.2 180)
			(layer "B.SilkS")
			(effects
				(font
					(size 0.7 0.7)
					(thickness 0.15)
				)
				(justify left bottom mirror)
			)
		)
		(property "Value" "C_100n_0402"
			(at 0 -1.169 180)
			(layer "B.Fab")
			(effects
				(font
					(size 0.7 0.7)
					(thickness 0.15)
				)
				(justify left bottom mirror)
			)
		)
		(property "Description" "SMD Multilayer Ceramic Capacitor, 0.1 µF, 50 V, 0402 [1005 Metric], ± 10%, X5R, GRM Series"
			(at 0 0 0)
			(layer "F.Fab")
			(hide yes)
			(effects
				(font
					(size 1.27 1.27)
					(thickness 0.15)
				)
			)
		)
		(property "Author" "Antmicro"
			(at 0 0 0)
			(layer "B.Fab")
			(hide yes)
			(effects
				(font
					(size 1 1)
					(thickness 0.15)
				)
				(justify mirror)
			)
		)
		(property "Dielectric" "X5R"
			(at 0 0 0)
			(layer "B.Fab")
			(hide yes)
			(effects
				(font
					(size 1 1)
					(thickness 0.15)
				)
				(justify mirror)
			)
		)
		(property "License" "Apache-2.0"
			(at 0 0 0)
			(layer "B.Fab")
			(hide yes)
			(effects
				(font
					(size 1 1)
					(thickness 0.15)
				)
				(justify mirror)
			)
		)
		(property "MPN" "GRM155R61H104KE14D"
			(at 0 0 0)
			(layer "B.Fab")
			(hide yes)
			(effects
				(font
					(size 1 1)
					(thickness 0.15)
				)
				(justify mirror)
			)
		)
		(property "Manufacturer" "Murata"
			(at 0 0 0)
			(layer "B.Fab")
			(hide yes)
			(effects
				(font
					(size 1 1)
					(thickness 0.15)
				)
				(justify mirror)
			)
		)
		(property "Val" "100n"
			(at 0 0 0)
			(layer "B.Fab")
			(hide yes)
			(effects
				(font
					(size 1 1)
					(thickness 0.15)
				)
				(justify mirror)
			)
		)
		(property "Voltage" "50V"
			(at 0 0 0)
			(layer "B.Fab")
			(hide yes)
			(effects
				(font
					(size 1 1)
					(thickness 0.15)
				)
				(justify mirror)
			)
		)
		(sheetname "FPGA supply")
		(sheetfile "fpga-supply.kicad_sch")
		(attr smd)
		(fp_rect
			(start -0.925 0.47)
			(end 0.925 -0.47)
			(stroke
				(width 0.05)
				(type default)
			)
			(fill no)
			(layer "B.CrtYd")
		)
		(fp_line
			(start -0.494 -0.248)
			(end -0.494 0.25)
			(stroke
				(width 0.15)
				(type solid)
			)
			(layer "B.Fab")
		)
		(fp_line
			(start -0.494 0.25)
			(end 0.504 0.25)
			(stroke
				(width 0.15)
				(type solid)
			)
			(layer "B.Fab")
		)
		(fp_line
			(start 0.504 -0.248)
			(end -0.494 -0.248)
			(stroke
				(width 0.15)
				(type solid)
			)
			(layer "B.Fab")
		)
		(fp_line
			(start 0.504 0.25)
			(end 0.504 -0.248)
			(stroke
				(width 0.15)
				(type solid)
			)
			(layer "B.Fab")
		)
		(pad "1" smd roundrect
			(at -0.48 0)
			(size 0.59 0.64)
			(layers "B.Cu" "B.Mask" "B.Paste")
			(roundrect_rratio 0.25)
			(net 6 "+1V0_MGTAVCC")
			(pintype "passive")
		)
		(pad "2" smd roundrect
			(at 0.48 0)
			(size 0.59 0.64)
			(layers "B.Cu" "B.Mask" "B.Paste")
			(roundrect_rratio 0.25)
			(net 1 "GND")
			(pintype "passive")
		)
	)
	(footprint "antmicro-footprints:R_0402_1005Metric"
		(layer "B.Cu")
		(at 175.33 177.26 180)
		(descr "Resistor SMD 0402")
		(tags "resistor SMD 0402")
		(property "Reference" "R277"
			(at -1.37 -2.215 0)
			(layer "B.SilkS")
			(effects
				(font
					(size 0.7 0.7)
					(thickness 0.15)
				)
				(justify left bottom mirror)
			)
		)
		(property "Value" "R_100k_0402"
			(at 0 -1.4 0)
			(layer "B.Fab")
			(effects
				(font
					(size 0.7 0.7)
					(thickness 0.15)
				)
				(justify left bottom mirror)
			)
		)
		(property "Description" "SMD Chip Resistor, 100 kohm, ± 1%, 62.5 mW, 0402 [1005 Metric], Thick Film, General Purpose"
			(at 0 0 180)
			(layer "F.Fab")
			(hide yes)
			(effects
				(font
					(size 1.27 1.27)
					(thickness 0.15)
				)
			)
		)
		(property "Author" "Antmicro"
			(at 350.66 354.52 0)
			(layer "B.Fab")
			(hide yes)
			(effects
				(font
					(size 1 1)
					(thickness 0.15)
				)
				(justify mirror)
			)
		)
		(property "DNP" "DNP"
			(at 350.66 354.52 0)
			(layer "B.Fab")
			(hide yes)
			(effects
				(font
					(size 1 1)
					(thickness 0.15)
				)
				(justify mirror)
			)
		)
		(property "License" "Apache-2.0"
			(at 350.66 354.52 0)
			(layer "B.Fab")
			(hide yes)
			(effects
				(font
					(size 1 1)
					(thickness 0.15)
				)
				(justify mirror)
			)
		)
		(property "MPN" "CR0402-FX-1003GLF"
			(at 350.66 354.52 0)
			(layer "B.Fab")
			(hide yes)
			(effects
				(font
					(size 1 1)
					(thickness 0.15)
				)
				(justify mirror)
			)
		)
		(property "Manufacturer" "Bourns"
			(at 350.66 354.52 0)
			(layer "B.Fab")
			(hide yes)
			(effects
				(font
					(size 1 1)
					(thickness 0.15)
				)
				(justify mirror)
			)
		)
		(property "Tolerance" "1%"
			(at 350.66 354.52 0)
			(layer "B.Fab")
			(hide yes)
			(effects
				(font
					(size 1 1)
					(thickness 0.15)
				)
				(justify mirror)
			)
		)
		(property "Val" "100k"
			(at 350.66 354.52 0)
			(layer "B.Fab")
			(hide yes)
			(effects
				(font
					(size 1 1)
					(thickness 0.15)
				)
				(justify mirror)
			)
		)
		(property "dnp" ""
			(at 350.66 354.52 0)
			(layer "B.Fab")
			(hide yes)
			(effects
				(font
					(size 1 1)
					(thickness 0.15)
				)
				(justify mirror)
			)
		)
		(property "exclude_from_bom" ""
			(at 350.66 354.52 0)
			(layer "B.Fab")
			(hide yes)
			(effects
				(font
					(size 1 1)
					(thickness 0.15)
				)
				(justify mirror)
			)
		)
		(sheetname "DC-DC Converters")
		(sheetfile "dc-dc.kicad_sch")
		(attr smd exclude_from_bom)
		(fp_rect
			(start -0.925 0.47)
			(end 0.925 -0.47)
			(stroke
				(width 0.05)
				(type default)
			)
			(fill no)
			(layer "B.CrtYd")
		)
		(fp_rect
			(start -0.5 0.25)
			(end 0.5 -0.25)
			(stroke
				(width 0.15)
				(type solid)
			)
			(fill no)
			(layer "B.Fab")
		)
		(pad "1" smd roundrect
			(at -0.48 0 180)
			(size 0.59 0.64)
			(layers "B.Cu" "B.Mask" "B.Paste")
			(roundrect_rratio 0.25)
			(net 954 "/DC-DC Converters/QDCDC2_GPIO")
			(pintype "passive")
		)
		(pad "2" smd roundrect
			(at 0.48 0 180)
			(size 0.59 0.64)
			(layers "B.Cu" "B.Mask" "B.Paste")
			(roundrect_rratio 0.25)
			(net 732 "/DC-DC Converters/QDCDC2_VCC")
			(pintype "passive")
		)
	)
	(footprint "antmicro-footprints:R_Array_4x0201_Panasonic_EXB18V"
		(layer "B.Cu")
		(at 247.901 127.9)
		(property "Reference" "R20"
			(at 1.024 -0.725 0)
			(layer "B.SilkS")
			(effects
				(font
					(size 0.7 0.7)
					(thickness 0.15)
				)
				(justify left bottom mirror)
			)
		)
		(property "Value" "R_4x33R_0201_array"
			(at -1.1 -1.8 0)
			(layer "B.Fab")
			(effects
				(font
					(size 0.7 0.7)
					(thickness 0.15)
				)
				(justify right bottom mirror)
			)
		)
		(property "Description" "Fixed Network Resistor, 33 ohm, Isolated, 4 Resistors, 0502 [1406 Metric], Flat, ± 5%"
			(at 0 0 0)
			(layer "F.Fab")
			(hide yes)
			(effects
				(font
					(size 1.27 1.27)
					(thickness 0.15)
				)
			)
		)
		(property "Author" "Antmicro"
			(at 0 0 0)
			(layer "B.Fab")
			(hide yes)
			(effects
				(font
					(size 1 1)
					(thickness 0.15)
				)
				(justify mirror)
			)
		)
		(property "License" "Apache-2.0"
			(at 0 0 0)
			(layer "B.Fab")
			(hide yes)
			(effects
				(font
					(size 1 1)
					(thickness 0.15)
				)
				(justify mirror)
			)
		)
		(property "MPN" "EXB-18V330JX"
			(at 0 0 0)
			(layer "B.Fab")
			(hide yes)
			(effects
				(font
					(size 1 1)
					(thickness 0.15)
				)
				(justify mirror)
			)
		)
		(property "Manufacturer" "Panasonic"
			(at 0 0 0)
			(layer "B.Fab")
			(hide yes)
			(effects
				(font
					(size 1 1)
					(thickness 0.15)
				)
				(justify mirror)
			)
		)
		(property "Val" "R_4x33R_0201"
			(at 0 0 0)
			(layer "B.Fab")
			(hide yes)
			(effects
				(font
					(size 1 1)
					(thickness 0.15)
				)
				(justify mirror)
			)
		)
		(sheetname "Supervisior MCU")
		(sheetfile "supervisor-mcu.kicad_sch")
		(attr smd)
		(fp_line
			(start -0.8 0.45)
			(end -0.8 -0.45)
			(stroke
				(width 0.12)
				(type solid)
			)
			(layer "B.SilkS")
		)
		(fp_line
			(start 0.8 0.45)
			(end 0.8 -0.45)
			(stroke
				(width 0.12)
				(type solid)
			)
			(layer "B.SilkS")
		)
		(fp_rect
			(start -0.898 0.66)
			(end 0.898 -0.65)
			(stroke
				(width 0.05)
				(type solid)
			)
			(fill no)
			(layer "B.CrtYd")
		)
		(pad "1" smd roundrect
			(at -0.6 -0.298)
			(size 0.2 0.4)
			(layers "B.Cu" "B.Mask" "B.Paste")
			(roundrect_rratio 0.25)
			(net 346 "unconnected-(R20-R1.1-Pad1)")
			(pinfunction "R1.1")
			(pintype "passive+no_connect")
		)
		(pad "2" smd roundrect
			(at -0.202 -0.298)
			(size 0.2 0.4)
			(layers "B.Cu" "B.Mask" "B.Paste")
			(roundrect_rratio 0.25)
			(net 1351 "/SUP_MCU.A0")
			(pinfunction "R2.1")
			(pintype "passive")
		)
		(pad "3" smd roundrect
			(at 0.2 -0.298)
			(size 0.2 0.4)
			(layers "B.Cu" "B.Mask" "B.Paste")
			(roundrect_rratio 0.25)
			(net 1330 "/SUP_MCU.RX1")
			(pinfunction "R3.1")
			(pintype "passive")
		)
		(pad "4" smd roundrect
			(at 0.598 -0.298)
			(size 0.2 0.4)
			(layers "B.Cu" "B.Mask" "B.Paste")
			(roundrect_rratio 0.25)
			(net 1352 "/SUP_MCU.A13")
			(pinfunction "R4.1")
			(pintype "passive")
		)
		(pad "5" smd roundrect
			(at 0.598 0.3)
			(size 0.2 0.4)
			(layers "B.Cu" "B.Mask" "B.Paste")
			(roundrect_rratio 0.25)
			(net 1074 "/Supervisior MCU/USB_A13")
			(pinfunction "R4.2")
			(pintype "passive")
		)
		(pad "6" smd roundrect
			(at 0.2 0.3)
			(size 0.2 0.4)
			(layers "B.Cu" "B.Mask" "B.Paste")
			(roundrect_rratio 0.25)
			(net 1083 "/Supervisior MCU/RXD1")
			(pinfunction "R3.2")
			(pintype "passive")
		)
		(pad "7" smd roundrect
			(at -0.202 0.3)
			(size 0.2 0.4)
			(layers "B.Cu" "B.Mask" "B.Paste")
			(roundrect_rratio 0.25)
			(net 1061 "/Supervisior MCU/USB_A0")
			(pinfunction "R2.2")
			(pintype "passive")
		)
		(pad "8" smd roundrect
			(at -0.6 0.3)
			(size 0.2 0.4)
			(layers "B.Cu" "B.Mask" "B.Paste")
			(roundrect_rratio 0.25)
			(net 347 "unconnected-(R20-R1.2-Pad8)")
			(pinfunction "R1.2")
			(pintype "passive+no_connect")
		)
	)
	(footprint "antmicro-footprints:R_Array_4x0201_Panasonic_EXB18V"
		(layer "B.Cu")
		(at 167.799999 144.999999)
		(property "Reference" "R12"
			(at -4.024999 6.250001 0)
			(layer "B.SilkS")
			(effects
				(font
					(size 0.7 0.7)
					(thickness 0.15)
				)
				(justify left bottom mirror)
			)
		)
		(property "Value" "4x39R_0201_array"
			(at -1.1 -1.8 0)
			(layer "B.Fab")
			(effects
				(font
					(size 0.7 0.7)
					(thickness 0.15)
				)
				(justify right bottom mirror)
			)
		)
		(property "Description" "Fixed Network Resistor, 39 ohm, Isolated, 4 Resistors, 0502 [1406 Metric], Flat, ± 5%"
			(at 0 0 0)
			(layer "F.Fab")
			(hide yes)
			(effects
				(font
					(size 1.27 1.27)
					(thickness 0.15)
				)
			)
		)
		(property "Author" "Antmicro"
			(at 0 0 0)
			(layer "B.Fab")
			(hide yes)
			(effects
				(font
					(size 1 1)
					(thickness 0.15)
				)
				(justify mirror)
			)
		)
		(property "License" "Apache-2.0"
			(at 0 0 0)
			(layer "B.Fab")
			(hide yes)
			(effects
				(font
					(size 1 1)
					(thickness 0.15)
				)
				(justify mirror)
			)
		)
		(property "MPN" "EXB-18V390JX"
			(at 0 0 0)
			(layer "B.Fab")
			(hide yes)
			(effects
				(font
					(size 1 1)
					(thickness 0.15)
				)
				(justify mirror)
			)
		)
		(property "Manufacturer" "Panasonic"
			(at 0 0 0)
			(layer "B.Fab")
			(hide yes)
			(effects
				(font
					(size 1 1)
					(thickness 0.15)
				)
				(justify mirror)
			)
		)
		(property "Val" "4x39R_0201"
			(at 0 0 0)
			(layer "B.Fab")
			(hide yes)
			(effects
				(font
					(size 1 1)
					(thickness 0.15)
				)
				(justify mirror)
			)
		)
		(sheetname "DRAM + SRAM")
		(sheetfile "ram.kicad_sch")
		(attr smd)
		(fp_line
			(start -0.8 0.45)
			(end -0.8 -0.45)
			(stroke
				(width 0.12)
				(type solid)
			)
			(layer "B.SilkS")
		)
		(fp_line
			(start 0.8 0.45)
			(end 0.8 -0.45)
			(stroke
				(width 0.12)
				(type solid)
			)
			(layer "B.SilkS")
		)
		(fp_rect
			(start -0.898 0.66)
			(end 0.898 -0.65)
			(stroke
				(width 0.05)
				(type solid)
			)
			(fill no)
			(layer "B.CrtYd")
		)
		(pad "1" smd roundrect
			(at -0.6 -0.298)
			(size 0.2 0.4)
			(layers "B.Cu" "B.Mask" "B.Paste")
			(roundrect_rratio 0.25)
			(net 549 "/DRAM + SRAM/DDR.BA2")
			(pinfunction "R1.1")
			(pintype "passive")
		)
		(pad "2" smd roundrect
			(at -0.202 -0.298)
			(size 0.2 0.4)
			(layers "B.Cu" "B.Mask" "B.Paste")
			(roundrect_rratio 0.25)
			(net 561 "/DRAM + SRAM/DDR.~{CS}")
			(pinfunction "R2.1")
			(pintype "passive")
		)
		(pad "3" smd roundrect
			(at 0.2 -0.298)
			(size 0.2 0.4)
			(layers "B.Cu" "B.Mask" "B.Paste")
			(roundrect_rratio 0.25)
			(net 558 "/DRAM + SRAM/DDR.~{WE}")
			(pinfunction "R3.1")
			(pintype "passive")
		)
		(pad "4" smd roundrect
			(at 0.598 -0.298)
			(size 0.2 0.4)
			(layers "B.Cu" "B.Mask" "B.Paste")
			(roundrect_rratio 0.25)
			(net 553 "/DRAM + SRAM/DDR.ODT")
			(pinfunction "R4.1")
			(pintype "passive")
		)
		(pad "5" smd roundrect
			(at 0.598 0.3)
			(size 0.2 0.4)
			(layers "B.Cu" "B.Mask" "B.Paste")
			(roundrect_rratio 0.25)
			(net 7 "+0V675_VTT")
			(pinfunction "R4.2")
			(pintype "passive")
		)
		(pad "6" smd roundrect
			(at 0.2 0.3)
			(size 0.2 0.4)
			(layers "B.Cu" "B.Mask" "B.Paste")
			(roundrect_rratio 0.25)
			(net 7 "+0V675_VTT")
			(pinfunction "R3.2")
			(pintype "passive")
		)
		(pad "7" smd roundrect
			(at -0.202 0.3)
			(size 0.2 0.4)
			(layers "B.Cu" "B.Mask" "B.Paste")
			(roundrect_rratio 0.25)
			(net 7 "+0V675_VTT")
			(pinfunction "R2.2")
			(pintype "passive")
		)
		(pad "8" smd roundrect
			(at -0.6 0.3)
			(size 0.2 0.4)
			(layers "B.Cu" "B.Mask" "B.Paste")
			(roundrect_rratio 0.25)
			(net 7 "+0V675_VTT")
			(pinfunction "R1.2")
			(pintype "passive")
		)
	)
	(footprint "antmicro-footprints:C_0402_1005Metric"
		(layer "B.Cu")
		(at 194.85 131.25)
		(descr "Capacitor SMD 0402")
		(tags "capacitor SMD 0402")
		(property "Reference" "C140"
			(at 24.425 -28.05 180)
			(layer "B.SilkS")
			(effects
				(font
					(size 0.7 0.7)
					(thickness 0.15)
				)
				(justify left bottom mirror)
			)
		)
		(property "Value" "C_100n_0402"
			(at 0 -1.169 180)
			(layer "B.Fab")
			(effects
				(font
					(size 0.7 0.7)
					(thickness 0.15)
				)
				(justify left bottom mirror)
			)
		)
		(property "Description" "SMD Multilayer Ceramic Capacitor, 0.1 µF, 50 V, 0402 [1005 Metric], ± 10%, X5R, GRM Series"
			(at 0 0 0)
			(layer "F.Fab")
			(hide yes)
			(effects
				(font
					(size 1.27 1.27)
					(thickness 0.15)
				)
			)
		)
		(property "Author" "Antmicro"
			(at 0 0 0)
			(layer "B.Fab")
			(hide yes)
			(effects
				(font
					(size 1 1)
					(thickness 0.15)
				)
				(justify mirror)
			)
		)
		(property "Dielectric" "X5R"
			(at 0 0 0)
			(layer "B.Fab")
			(hide yes)
			(effects
				(font
					(size 1 1)
					(thickness 0.15)
				)
				(justify mirror)
			)
		)
		(property "License" "Apache-2.0"
			(at 0 0 0)
			(layer "B.Fab")
			(hide yes)
			(effects
				(font
					(size 1 1)
					(thickness 0.15)
				)
				(justify mirror)
			)
		)
		(property "MPN" "GRM155R61H104KE14D"
			(at 0 0 0)
			(layer "B.Fab")
			(hide yes)
			(effects
				(font
					(size 1 1)
					(thickness 0.15)
				)
				(justify mirror)
			)
		)
		(property "Manufacturer" "Murata"
			(at 0 0 0)
			(layer "B.Fab")
			(hide yes)
			(effects
				(font
					(size 1 1)
					(thickness 0.15)
				)
				(justify mirror)
			)
		)
		(property "Val" "100n"
			(at 0 0 0)
			(layer "B.Fab")
			(hide yes)
			(effects
				(font
					(size 1 1)
					(thickness 0.15)
				)
				(justify mirror)
			)
		)
		(property "Voltage" "50V"
			(at 0 0 0)
			(layer "B.Fab")
			(hide yes)
			(effects
				(font
					(size 1 1)
					(thickness 0.15)
				)
				(justify mirror)
			)
		)
		(sheetname "FPGA supply")
		(sheetfile "fpga-supply.kicad_sch")
		(attr smd)
		(fp_rect
			(start -0.925 0.47)
			(end 0.925 -0.47)
			(stroke
				(width 0.05)
				(type default)
			)
			(fill no)
			(layer "B.CrtYd")
		)
		(fp_line
			(start -0.494 -0.248)
			(end -0.494 0.25)
			(stroke
				(width 0.15)
				(type solid)
			)
			(layer "B.Fab")
		)
		(fp_line
			(start -0.494 0.25)
			(end 0.504 0.25)
			(stroke
				(width 0.15)
				(type solid)
			)
			(layer "B.Fab")
		)
		(fp_line
			(start 0.504 -0.248)
			(end -0.494 -0.248)
			(stroke
				(width 0.15)
				(type solid)
			)
			(layer "B.Fab")
		)
		(fp_line
			(start 0.504 0.25)
			(end 0.504 -0.248)
			(stroke
				(width 0.15)
				(type solid)
			)
			(layer "B.Fab")
		)
		(pad "1" smd roundrect
			(at -0.48 0)
			(size 0.59 0.64)
			(layers "B.Cu" "B.Mask" "B.Paste")
			(roundrect_rratio 0.25)
			(net 1 "GND")
			(pintype "passive")
		)
		(pad "2" smd roundrect
			(at 0.48 0)
			(size 0.59 0.64)
			(layers "B.Cu" "B.Mask" "B.Paste")
			(roundrect_rratio 0.25)
			(net 650 "+1V0")
			(pintype "passive")
		)
	)
)
